# S9S_MB_2U (Grand Teton) — schematic netlist excerpt (pin names and nets, part order shuffled) for the footprints in the layout excerpt that follows; sources: Cadence DE-HDL packaged netlist, KiCad conversion of 03242023_DA0F0TMBIJ0_F0T_Motherboard_J_brd_V01_OCP.brd

PC1213_P0_3  Q_CAP  2.2UF 10V 10% X6S  pkg C0402  page 272 : A = PVCCFA_EHV_FIVRA_CPU0_PVCC1 ; B = GND
C1531  Q_CAP_DIFFBUS  DIFF BUS_0.22UF 6.3V 20% X6S  pkg C0201  page 177 : \1\ = P5E_CPU1_PE3_TX_C_DP<8> ; \2\ = P5E_CPU1_PE3_TX_DP<8>
C220  Q_CAP  47UF 4V 20% X6S  pkg C0805  page 74 : A = PVCCIN_CPU0 ; B = GND
C943  Q_CAP_DIFFBUS  DIFF BUS_0.22UF 6.3V 20% X6S  pkg C0201  page 173 : \1\ = P5E_CPU0_PE2_TX_C_DP<11> ; \2\ = P5E_CPU0_PE2_TX_DP<11>

(kicad_pcb
	(version 20260206)
	(generator "pcbnew")
	(generator_version "10.0")
	(general
		(thickness 1.6)
		(legacy_teardrops no)
	)
	(paper "A4")
	(title_block
		(title "03242023_DA0F0TMBIJ0_F0T_Motherboard_J_brd_V01_OCP.brd")
		(comment 1 "Grand Teton / footprints 3473-3476 of 6105")
	)
	(layers
		(0 "F.Cu" signal "TOP")
		(4 "In1.Cu" signal "GND")
		(6 "In2.Cu" signal "IN1")
		(8 "In3.Cu" signal "GND1")
		(10 "In4.Cu" signal "IN2")
		(12 "In5.Cu" signal "GND2")
		(14 "In6.Cu" signal "IN3")
		(16 "In7.Cu" signal "GND3")
		(18 "In8.Cu" signal "VCC")
		(20 "In9.Cu" signal "VCC1")
		(22 "In10.Cu" signal "GND4")
		(24 "In11.Cu" signal "IN4")
		(26 "In12.Cu" signal "GND5")
		(28 "In13.Cu" signal "IN5")
		(30 "In14.Cu" signal "GND6")
		(32 "In15.Cu" signal "IN6")
		(34 "In16.Cu" signal "GND7")
		(2 "B.Cu" signal "BOTTOM")
		(9 "F.Adhes" user "F.Adhesive")
		(11 "B.Adhes" user "B.Adhesive")
		(13 "F.Paste" user "Package Geometry/Pastemask Top")
		(15 "B.Paste" user "Package Geometry/Pastemask Bottom")
		(5 "F.SilkS" user "Ref Des/Silkscreen Top")
		(7 "B.SilkS" user "Ref Des/Silkscreen Bottom")
		(1 "F.Mask" user "Board Geometry/Soldermask Top")
		(3 "B.Mask" user "Board Geometry/Soldermask Bottom")
		(17 "Dwgs.User" user "User.Drawings")
		(19 "Cmts.User" user "User.Comments")
		(21 "Eco1.User" user "User.Eco1")
		(23 "Eco2.User" user "User.Eco2")
		(25 "Edge.Cuts" user "Board Geometry/Outline")
		(27 "Margin" user)
		(31 "F.CrtYd" user "Package Geometry/Place Bound Top")
		(29 "B.CrtYd" user "Package Geometry/Place Bound Bottom")
		(35 "F.Fab" user "Ref Des/Assembly Top")
		(33 "B.Fab" user "Ref Des/Assembly Bottom")
	)
	(footprint ""
		(layer "F.Cu")
		(at 422.273984 -361.896914 -90)
		(property "Reference" "PC1213_P0_3"
			(at 0 0 270)
			(layer "F.SilkS")
			(hide yes)
			(effects
				(font
					(size 1.27 1.27)
				)
			)
		)
		(property "Value" ""
			(at 0 0 270)
			(layer "F.Fab")
			(effects
				(font
					(size 1.27 1.27)
				)
			)
		)
		(duplicate_pad_numbers_are_jumpers no)
		(fp_line
			(start -0.7874 0.4064)
			(end -0.7874 -0.4064)
			(stroke
				(width 0.1524)
				(type default)
			)
			(layer "F.SilkS")
		)
		(fp_line
			(start 0.7874 0.4064)
			(end -0.7874 0.4064)
			(stroke
				(width 0.1524)
				(type default)
			)
			(layer "F.SilkS")
		)
		(fp_line
			(start -0.7874 -0.4064)
			(end 0.7874 -0.4064)
			(stroke
				(width 0.1524)
				(type default)
			)
			(layer "F.SilkS")
		)
		(fp_line
			(start 0.7874 -0.4064)
			(end 0.7874 0.4064)
			(stroke
				(width 0.1524)
				(type default)
			)
			(layer "F.SilkS")
		)
		(fp_line
			(start -0.67945 0.3048)
			(end -0.67945 -0.305054)
			(stroke
				(width 0.1)
				(type default)
			)
			(layer "F.Fab")
		)
		(fp_line
			(start -0.12065 0.3048)
			(end -0.67945 0.3048)
			(stroke
				(width 0.1)
				(type default)
			)
			(layer "F.Fab")
		)
		(fp_line
			(start 0.120396 0.3048)
			(end 0.120396 0.2794)
			(stroke
				(width 0.1)
				(type default)
			)
			(layer "F.Fab")
		)
		(fp_line
			(start 0.67945 0.3048)
			(end 0.120396 0.3048)
			(stroke
				(width 0.1)
				(type default)
			)
			(layer "F.Fab")
		)
		(fp_line
			(start -0.12065 0.2794)
			(end -0.12065 0.3048)
			(stroke
				(width 0.1)
				(type default)
			)
			(layer "F.Fab")
		)
		(fp_line
			(start 0.120396 0.2794)
			(end -0.12065 0.2794)
			(stroke
				(width 0.1)
				(type default)
			)
			(layer "F.Fab")
		)
		(fp_line
			(start -0.12065 -0.2794)
			(end 0.12065 -0.2794)
			(stroke
				(width 0.1)
				(type default)
			)
			(layer "F.Fab")
		)
		(fp_line
			(start 0.12065 -0.2794)
			(end 0.12065 -0.3048)
			(stroke
				(width 0.1)
				(type default)
			)
			(layer "F.Fab")
		)
		(fp_line
			(start 0.12065 -0.3048)
			(end 0.67945 -0.3048)
			(stroke
				(width 0.1)
				(type default)
			)
			(layer "F.Fab")
		)
		(fp_line
			(start 0.67945 -0.3048)
			(end 0.67945 0.3048)
			(stroke
				(width 0.1)
				(type default)
			)
			(layer "F.Fab")
		)
		(fp_line
			(start -0.67945 -0.305054)
			(end -0.12065 -0.305054)
			(stroke
				(width 0.1)
				(type default)
			)
			(layer "F.Fab")
		)
		(fp_line
			(start -0.12065 -0.305054)
			(end -0.12065 -0.2794)
			(stroke
				(width 0.1)
				(type default)
			)
			(layer "F.Fab")
		)
		(pad "1" smd circle
			(at -0.40005 0 270)
			(size 0 0)
			(layers "F.Cu" "F.Mask" "F.Paste")
			(net "PVCCFA_EHV_FIVRA_CPU0_PVCC1")
		)
		(pad "2" smd circle
			(at 0.40005 0 270)
			(size 0 0)
			(layers "F.Cu" "F.Mask" "F.Paste")
			(net "GND")
		)
	)
	(footprint ""
		(layer "F.Cu")
		(at 383.65049 -402.371052 -90)
		(property "Reference" "C943"
			(at 0 0 270)
			(layer "F.SilkS")
			(hide yes)
			(effects
				(font
					(size 1.27 1.27)
				)
			)
		)
		(property "Value" ""
			(at 0 0 270)
			(layer "F.Fab")
			(effects
				(font
					(size 1.27 1.27)
				)
			)
		)
		(duplicate_pad_numbers_are_jumpers no)
		(fp_line
			(start -0.299974 0.150114)
			(end -0.299974 -0.150114)
			(stroke
				(width 0.1)
				(type default)
			)
			(layer "F.Fab")
		)
		(fp_line
			(start 0.299974 0.150114)
			(end -0.299974 0.150114)
			(stroke
				(width 0.1)
				(type default)
			)
			(layer "F.Fab")
		)
		(fp_line
			(start -0.299974 -0.150114)
			(end 0.299974 -0.150114)
			(stroke
				(width 0.1)
				(type default)
			)
			(layer "F.Fab")
		)
		(fp_line
			(start 0.299974 -0.150114)
			(end 0.299974 0.150114)
			(stroke
				(width 0.1)
				(type default)
			)
			(layer "F.Fab")
		)
		(pad "1" smd rect
			(at -0.2667 0 270)
			(size 0.3048 0.381)
			(layers "F.Cu" "F.Mask" "F.Paste")
			(net "P5E_CPU0_PE2_TX_C_DP<11>")
		)
		(pad "2" smd rect
			(at 0.2667 0 270)
			(size 0.3048 0.381)
			(layers "F.Cu" "F.Mask" "F.Paste")
			(net "P5E_CPU0_PE2_TX_DP<11>")
		)
	)
	(footprint ""
		(layer "F.Cu")
		(at 143.832834 -408.517344 -90)
		(property "Reference" "C1531"
			(at 0 0 270)
			(layer "F.SilkS")
			(hide yes)
			(effects
				(font
					(size 1.27 1.27)
				)
			)
		)
		(property "Value" ""
			(at 0 0 270)
			(layer "F.Fab")
			(effects
				(font
					(size 1.27 1.27)
				)
			)
		)
		(duplicate_pad_numbers_are_jumpers no)
		(fp_line
			(start -0.299974 0.150114)
			(end -0.299974 -0.150114)
			(stroke
				(width 0.1)
				(type default)
			)
			(layer "F.Fab")
		)
		(fp_line
			(start 0.299974 0.150114)
			(end -0.299974 0.150114)
			(stroke
				(width 0.1)
				(type default)
			)
			(layer "F.Fab")
		)
		(fp_line
			(start -0.299974 -0.150114)
			(end 0.299974 -0.150114)
			(stroke
				(width 0.1)
				(type default)
			)
			(layer "F.Fab")
		)
		(fp_line
			(start 0.299974 -0.150114)
			(end 0.299974 0.150114)
			(stroke
				(width 0.1)
				(type default)
			)
			(layer "F.Fab")
		)
		(pad "1" smd rect
			(at -0.2667 0 270)
			(size 0.3048 0.381)
			(layers "F.Cu" "F.Mask" "F.Paste")
			(net "P5E_CPU1_PE3_TX_C_DP<8>")
		)
		(pad "2" smd rect
			(at 0.2667 0 270)
			(size 0.3048 0.381)
			(layers "F.Cu" "F.Mask" "F.Paste")
			(net "P5E_CPU1_PE3_TX_DP<8>")
		)
	)
	(footprint ""
		(layer "F.Cu")
		(at 366.06988 -294.01008 180)
		(property "Reference" "C220"
			(at 0 0 180)
			(layer "F.SilkS")
			(hide yes)
			(effects
				(font
					(size 1.27 1.27)
				)
			)
		)
		(property "Value" ""
			(at 0 0 180)
			(layer "F.Fab")
			(effects
				(font
					(size 1.27 1.27)
				)
			)
		)
		(duplicate_pad_numbers_are_jumpers no)
		(fp_line
			(start 1.524 0.762)
			(end -1.524 0.762)
			(stroke
				(width 0.1524)
				(type default)
			)
			(layer "F.SilkS")
		)
		(fp_line
			(start 1.524 -0.762)
			(end 1.524 0.762)
			(stroke
				(width 0.1524)
				(type default)
			)
			(layer "F.SilkS")
		)
		(fp_line
			(start -1.524 0.762)
			(end -1.524 -0.762)
			(stroke
				(width 0.1524)
				(type default)
			)
			(layer "F.SilkS")
		)
		(fp_line
			(start -1.524 -0.762)
			(end 1.524 -0.762)
			(stroke
				(width 0.1524)
				(type default)
			)
			(layer "F.SilkS")
		)
		(fp_line
			(start 1.1049 0.724916)
			(end 1.1049 -0.724916)
			(stroke
				(width 0.1)
				(type default)
			)
			(layer "F.Fab")
		)
		(fp_line
			(start 1.1049 -0.724916)
			(end -1.1049 -0.724916)
			(stroke
				(width 0.1)
				(type default)
			)
			(layer "F.Fab")
		)
		(fp_line
			(start -1.1049 0.724916)
			(end 1.1049 0.724916)
			(stroke
				(width 0.1)
				(type default)
			)
			(layer "F.Fab")
		)
		(fp_line
			(start -1.1049 -0.724916)
			(end -1.1049 0.724916)
			(stroke
				(width 0.1)
				(type default)
			)
			(layer "F.Fab")
		)
		(pad "1" smd rect
			(at -0.889 0)
			(size 1.016 1.27)
			(layers "F.Cu" "F.Mask" "F.Paste")
			(net "PVCCIN_CPU0")
		)
		(pad "2" smd rect
			(at 0.889 0)
			(size 1.016 1.27)
			(layers "F.Cu" "F.Mask" "F.Paste")
			(net "GND")
		)
	)
)
